FILE_TYPE = MULTI_PHYS_TABLE;

PART 'TUSB211IRWBR'

{========================================================================================}
:VALUE          | PART_TYPE | MATERIAL | PART_NUMBER    = STANDARD    | LIFECYCLE     | PART_NUMBER   | JEDEC_TYPE            | DESCRIPTION                       | MANUFTR | MANUF_PN       | RD_CMPLS_LVL | CMPLS_LVL | FROM_PJ     | CLASS | DIP_SMD | DATA                   | EE_CHECK_LIST | FP_ECN | PSL | CREATOR | STATUS | CREATEDAY  ;
{========================================================================================}
 'TUSB211IRWBR' | 'SMLF'    | 'IC'     | 'AL000211007'(!) = ''               | ''               | 'AL000211007' |'X2QFN12_0-4_1-6X1-6'| 'IC OTHER(12P) TUSB211IRWBR(QFN)' | 'TIC'   | 'TUSB211IRWBR' | 'EP(V1)'     | ''        | 'S5A-ROGER' | 'IC'  | ''      | 'TIC_TUSB211IRWBR.pdf' | ''            | ''     | ''  | ''      | ''     | '20150203'
 'TUSB211IRWBR' | 'SMLF'    | 'EMPTY'  | 'AL000211007'(!) = ''               | ''               | 'AL000211007' |'X2QFN12_0-4_1-6X1-6'| 'IC OTHER(12P) TUSB211IRWBR(QFN)' | 'TIC'   | 'TUSB211IRWBR' | 'EP(V1)'     | ''        | 'S5A-ROGER' | 'IC'  | ''      | 'TIC_TUSB211IRWBR.pdf' | ''            | ''     | ''  | ''      | ''     | '20150203'

END_PART

END.

